# T6G (Grand Teton) — schematic netlist excerpt (pin names and nets, part order shuffled) for the footprints in the layout excerpt that follows; sources: Cadence DE-HDL packaged netlist, KiCad conversion of 04192023_DAF0TMB3IC0_F0TG_MB_C_brd_V02_OCP.brd

R986  Q_RES  0 5% EMPTY  pkg 0402LF  page 159 : A = I3C_1_SPD_DDRGL_CPU0_R_SCL ; B = I3C_SPD_DDRGL_CPU0_BYPASS_SCL
R6764  Q_RES  1K 1% CHIP  pkg 0201LF  page 184 : A = P1V8_CPU0_RT_1D ; B = SMB_RT_CPU0_P1_R_SDA
R161  Q_RES  33 5% CHIP  pkg 0402LF  page 81 : A = CPU1_JTAG_BUF_R_OE ; B = CPU1_JTAG_BUF_OE

(kicad_pcb
	(version 20260206)
	(generator "pcbnew")
	(generator_version "10.0")
	(general
		(thickness 1.6)
		(legacy_teardrops no)
	)
	(paper "A4")
	(title_block
		(title "04192023_DAF0TMB3IC0_F0TG_MB_C_brd_V02_OCP.brd")
		(comment 1 "Grand Teton / footprints 6871-6873 of 8354")
	)
	(layers
		(0 "F.Cu" signal "TOP")
		(4 "In1.Cu" signal "GND")
		(6 "In2.Cu" signal "IN1")
		(8 "In3.Cu" signal "GND1")
		(10 "In4.Cu" signal "IN2")
		(12 "In5.Cu" signal "GND2")
		(14 "In6.Cu" signal "IN3")
		(16 "In7.Cu" signal "GND3")
		(18 "In8.Cu" signal "VCC")
		(20 "In9.Cu" signal "VCC1")
		(22 "In10.Cu" signal "GND4")
		(24 "In11.Cu" signal "IN4")
		(26 "In12.Cu" signal "GND5")
		(28 "In13.Cu" signal "IN5")
		(30 "In14.Cu" signal "GND6")
		(32 "In15.Cu" signal "IN6")
		(34 "In16.Cu" signal "GND7")
		(2 "B.Cu" signal "BOTTOM")
		(9 "F.Adhes" user "F.Adhesive")
		(11 "B.Adhes" user "B.Adhesive")
		(13 "F.Paste" user "Package Geometry/Pastemask Top")
		(15 "B.Paste" user "Package Geometry/Pastemask Bottom")
		(5 "F.SilkS" user "Ref Des/Silkscreen Top")
		(7 "B.SilkS" user "Ref Des/Silkscreen Bottom")
		(1 "F.Mask" user "Board Geometry/Soldermask Top")
		(3 "B.Mask" user "Board Geometry/Soldermask Bottom")
		(17 "Dwgs.User" user "User.Drawings")
		(19 "Cmts.User" user "User.Comments")
		(21 "Eco1.User" user "User.Eco1")
		(23 "Eco2.User" user "User.Eco2")
		(25 "Edge.Cuts" user "Board Geometry/Outline")
		(27 "Margin" user)
		(31 "F.CrtYd" user "Package Geometry/Place Bound Top")
		(29 "B.CrtYd" user "Package Geometry/Place Bound Bottom")
		(35 "F.Fab" user "Ref Des/Assembly Top")
		(33 "B.Fab" user "Ref Des/Assembly Bottom")
	)
	(footprint ""
		(layer "B.Cu")
		(at 380.282958 -205.902052 -90)
		(property "Reference" "R986"
			(at 0 0 90)
			(layer "B.SilkS")
			(hide yes)
			(effects
				(font
					(size 1.27 1.27)
				)
				(justify mirror)
			)
		)
		(property "Value" ""
			(at 0 0 90)
			(layer "B.Fab")
			(effects
				(font
					(size 1.27 1.27)
				)
				(justify mirror)
			)
		)
		(duplicate_pad_numbers_are_jumpers no)
		(fp_line
			(start -0.7874 0.4064)
			(end 0.7874 0.4064)
			(stroke
				(width 0.1524)
				(type default)
			)
			(layer "B.SilkS")
		)
		(fp_line
			(start 0.7874 0.4064)
			(end 0.7874 -0.4064)
			(stroke
				(width 0.1524)
				(type default)
			)
			(layer "B.SilkS")
		)
		(fp_line
			(start -0.7874 -0.4064)
			(end -0.7874 0.4064)
			(stroke
				(width 0.1524)
				(type default)
			)
			(layer "B.SilkS")
		)
		(fp_line
			(start 0.7874 -0.4064)
			(end -0.7874 -0.4064)
			(stroke
				(width 0.1524)
				(type default)
			)
			(layer "B.SilkS")
		)
		(fp_line
			(start -0.67945 0.3048)
			(end -0.120396 0.3048)
			(stroke
				(width 0.1)
				(type default)
			)
			(layer "B.Fab")
		)
		(fp_line
			(start -0.120396 0.3048)
			(end -0.120396 0.2794)
			(stroke
				(width 0.1)
				(type default)
			)
			(layer "B.Fab")
		)
		(fp_line
			(start 0.12065 0.3048)
			(end 0.67945 0.3048)
			(stroke
				(width 0.1)
				(type default)
			)
			(layer "B.Fab")
		)
		(fp_line
			(start 0.67945 0.3048)
			(end 0.67945 -0.305054)
			(stroke
				(width 0.1)
				(type default)
			)
			(layer "B.Fab")
		)
		(fp_line
			(start -0.120396 0.2794)
			(end 0.12065 0.2794)
			(stroke
				(width 0.1)
				(type default)
			)
			(layer "B.Fab")
		)
		(fp_line
			(start 0.12065 0.2794)
			(end 0.12065 0.3048)
			(stroke
				(width 0.1)
				(type default)
			)
			(layer "B.Fab")
		)
		(fp_line
			(start -0.12065 -0.2794)
			(end -0.12065 -0.3048)
			(stroke
				(width 0.1)
				(type default)
			)
			(layer "B.Fab")
		)
		(fp_line
			(start 0.12065 -0.2794)
			(end -0.12065 -0.2794)
			(stroke
				(width 0.1)
				(type default)
			)
			(layer "B.Fab")
		)
		(fp_line
			(start -0.67945 -0.3048)
			(end -0.67945 0.3048)
			(stroke
				(width 0.1)
				(type default)
			)
			(layer "B.Fab")
		)
		(fp_line
			(start -0.12065 -0.3048)
			(end -0.67945 -0.3048)
			(stroke
				(width 0.1)
				(type default)
			)
			(layer "B.Fab")
		)
		(fp_line
			(start 0.12065 -0.305054)
			(end 0.12065 -0.2794)
			(stroke
				(width 0.1)
				(type default)
			)
			(layer "B.Fab")
		)
		(fp_line
			(start 0.67945 -0.305054)
			(end 0.12065 -0.305054)
			(stroke
				(width 0.1)
				(type default)
			)
			(layer "B.Fab")
		)
		(pad "1" smd rect
			(at 0.40005 0 270)
			(size 0.4572 0.508)
			(layers "B.Cu" "B.Mask" "B.Paste")
			(net "I3C_1_SPD_DDRGL_CPU0_R_SCL")
		)
		(pad "2" smd rect
			(at -0.40005 0 270)
			(size 0.4572 0.508)
			(layers "B.Cu" "B.Mask" "B.Paste")
			(net "I3C_SPD_DDRGL_CPU0_BYPASS_SCL")
		)
	)
	(footprint ""
		(layer "B.Cu")
		(at 232.537 -339.725 90)
		(property "Reference" "R6764"
			(at 0 0 90)
			(layer "B.SilkS")
			(hide yes)
			(effects
				(font
					(size 1.27 1.27)
				)
				(justify mirror)
			)
		)
		(property "Value" ""
			(at 0 0 90)
			(layer "B.Fab")
			(effects
				(font
					(size 1.27 1.27)
				)
				(justify mirror)
			)
		)
		(duplicate_pad_numbers_are_jumpers no)
		(fp_line
			(start 0.32512 -0.175006)
			(end -0.32512 -0.175006)
			(stroke
				(width 0.1)
				(type default)
			)
			(layer "B.Fab")
		)
		(fp_line
			(start -0.32512 -0.175006)
			(end -0.32512 0.175006)
			(stroke
				(width 0.1)
				(type default)
			)
			(layer "B.Fab")
		)
		(fp_line
			(start 0.32512 0.175006)
			(end 0.32512 -0.175006)
			(stroke
				(width 0.1)
				(type default)
			)
			(layer "B.Fab")
		)
		(fp_line
			(start -0.32512 0.175006)
			(end 0.32512 0.175006)
			(stroke
				(width 0.1)
				(type default)
			)
			(layer "B.Fab")
		)
		(pad "1" smd rect
			(at 0.2667 0 270)
			(size 0.3048 0.381)
			(layers "B.Cu" "B.Mask" "B.Paste")
			(net "P1V8_CPU0_RT_1D")
		)
		(pad "2" smd rect
			(at -0.2667 0 90)
			(size 0.3048 0.381)
			(layers "B.Cu" "B.Mask" "B.Paste")
			(net "SMB_RT_CPU0_P1_R_SDA")
		)
	)
	(footprint ""
		(layer "B.Cu")
		(at 187.055506 -126.833376 -90)
		(property "Reference" "R161"
			(at 0 0 90)
			(layer "B.SilkS")
			(hide yes)
			(effects
				(font
					(size 1.27 1.27)
				)
				(justify mirror)
			)
		)
		(property "Value" ""
			(at 0 0 90)
			(layer "B.Fab")
			(effects
				(font
					(size 1.27 1.27)
				)
				(justify mirror)
			)
		)
		(duplicate_pad_numbers_are_jumpers no)
		(fp_line
			(start -0.7874 0.4064)
			(end 0.7874 0.4064)
			(stroke
				(width 0.1524)
				(type default)
			)
			(layer "B.SilkS")
		)
		(fp_line
			(start 0.7874 0.4064)
			(end 0.7874 -0.4064)
			(stroke
				(width 0.1524)
				(type default)
			)
			(layer "B.SilkS")
		)
		(fp_line
			(start -0.7874 -0.4064)
			(end -0.7874 0.4064)
			(stroke
				(width 0.1524)
				(type default)
			)
			(layer "B.SilkS")
		)
		(fp_line
			(start 0.7874 -0.4064)
			(end -0.7874 -0.4064)
			(stroke
				(width 0.1524)
				(type default)
			)
			(layer "B.SilkS")
		)
		(fp_line
			(start -0.67945 0.3048)
			(end -0.120396 0.3048)
			(stroke
				(width 0.1)
				(type default)
			)
			(layer "B.Fab")
		)
		(fp_line
			(start -0.120396 0.3048)
			(end -0.120396 0.2794)
			(stroke
				(width 0.1)
				(type default)
			)
			(layer "B.Fab")
		)
		(fp_line
			(start 0.12065 0.3048)
			(end 0.67945 0.3048)
			(stroke
				(width 0.1)
				(type default)
			)
			(layer "B.Fab")
		)
		(fp_line
			(start 0.67945 0.3048)
			(end 0.67945 -0.305054)
			(stroke
				(width 0.1)
				(type default)
			)
			(layer "B.Fab")
		)
		(fp_line
			(start -0.120396 0.2794)
			(end 0.12065 0.2794)
			(stroke
				(width 0.1)
				(type default)
			)
			(layer "B.Fab")
		)
		(fp_line
			(start 0.12065 0.2794)
			(end 0.12065 0.3048)
			(stroke
				(width 0.1)
				(type default)
			)
			(layer "B.Fab")
		)
		(fp_line
			(start -0.12065 -0.2794)
			(end -0.12065 -0.3048)
			(stroke
				(width 0.1)
				(type default)
			)
			(layer "B.Fab")
		)
		(fp_line
			(start 0.12065 -0.2794)
			(end -0.12065 -0.2794)
			(stroke
				(width 0.1)
				(type default)
			)
			(layer "B.Fab")
		)
		(fp_line
			(start -0.67945 -0.3048)
			(end -0.67945 0.3048)
			(stroke
				(width 0.1)
				(type default)
			)
			(layer "B.Fab")
		)
		(fp_line
			(start -0.12065 -0.3048)
			(end -0.67945 -0.3048)
			(stroke
				(width 0.1)
				(type default)
			)
			(layer "B.Fab")
		)
		(fp_line
			(start 0.12065 -0.305054)
			(end 0.12065 -0.2794)
			(stroke
				(width 0.1)
				(type default)
			)
			(layer "B.Fab")
		)
		(fp_line
			(start 0.67945 -0.305054)
			(end 0.12065 -0.305054)
			(stroke
				(width 0.1)
				(type default)
			)
			(layer "B.Fab")
		)
		(pad "1" smd circle
			(at 0.40005 0 90)
			(size 0 0)
			(layers "B.Cu" "B.Mask" "B.Paste")
			(net "CPU1_JTAG_BUF_R_OE")
		)
		(pad "2" smd circle
			(at -0.40005 0 90)
			(size 0 0)
			(layers "B.Cu" "B.Mask" "B.Paste")
			(net "CPU1_JTAG_BUF_OE")
		)
	)
)
